(kicad_pcb
	(version 20260206)
	(generator "pcbnew")
	(generator_version "10.0")
	(general
		(thickness 1.6)
		(legacy_teardrops no)
	)
	(paper "A4")
	(title_block
		(title "01162023_DA0F0TEBIF0_F0T_Expander_BD_F_brd_V02_OCP.brd")
		(comment 1 "Grand Teton / footprints 2593-2599 of 9728")
	)
	(layers
		(0 "F.Cu" signal "TOP")
		(4 "In1.Cu" signal "GND")
		(6 "In2.Cu" signal "VCC")
		(8 "In3.Cu" signal "VCC1")
		(10 "In4.Cu" signal "GND1")
		(12 "In5.Cu" signal "IN1")
		(14 "In6.Cu" signal "GND2")
		(16 "In7.Cu" signal "IN2")
		(18 "In8.Cu" signal "GND3")
		(20 "In9.Cu" signal "IN3")
		(22 "In10.Cu" signal "GND4")
		(24 "In11.Cu" signal "IN4")
		(26 "In12.Cu" signal "GND5")
		(28 "In13.Cu" signal "IN5")
		(30 "In14.Cu" signal "GND6")
		(32 "In15.Cu" signal "IN6")
		(34 "In16.Cu" signal "GND7")
		(2 "B.Cu" signal "BOTTOM")
		(9 "F.Adhes" user "F.Adhesive")
		(11 "B.Adhes" user "B.Adhesive")
		(13 "F.Paste" user "Package Geometry/Pastemask Top")
		(15 "B.Paste" user "Package Geometry/Pastemask Bottom")
		(5 "F.SilkS" user "Ref Des/Silkscreen Top")
		(7 "B.SilkS" user "Ref Des/Silkscreen Bottom")
		(1 "F.Mask" user "Board Geometry/Soldermask Top")
		(3 "B.Mask" user "Board Geometry/Soldermask Bottom")
		(17 "Dwgs.User" user "User.Drawings")
		(19 "Cmts.User" user "User.Comments")
		(21 "Eco1.User" user "User.Eco1")
		(23 "Eco2.User" user "User.Eco2")
		(25 "Edge.Cuts" user "Board Geometry/Outline")
		(27 "Margin" user)
		(31 "F.CrtYd" user "Package Geometry/Place Bound Top")
		(29 "B.CrtYd" user "Package Geometry/Place Bound Bottom")
		(35 "F.Fab" user "Ref Des/Assembly Top")
		(33 "B.Fab" user "Ref Des/Assembly Bottom")
	)
	(footprint ""
		(layer "F.Cu")
		(at 331.175614 -122.525028)
		(property "Reference" "PC468"
			(at 0 0 0)
			(layer "F.SilkS")
			(hide yes)
			(effects
				(font
					(size 1.27 1.27)
				)
			)
		)
		(property "Value" ""
			(at 0 0 0)
			(layer "F.Fab")
			(effects
				(font
					(size 1.27 1.27)
				)
			)
		)
		(duplicate_pad_numbers_are_jumpers no)
		(fp_line
			(start -0.7874 -0.4064)
			(end 0.7874 -0.4064)
			(stroke
				(width 0.1524)
				(type default)
			)
			(layer "F.SilkS")
		)
		(fp_line
			(start -0.7874 0.4064)
			(end -0.7874 -0.4064)
			(stroke
				(width 0.1524)
				(type default)
			)
			(layer "F.SilkS")
		)
		(fp_line
			(start 0.7874 -0.4064)
			(end 0.7874 0.4064)
			(stroke
				(width 0.1524)
				(type default)
			)
			(layer "F.SilkS")
		)
		(fp_line
			(start 0.7874 0.4064)
			(end -0.7874 0.4064)
			(stroke
				(width 0.1524)
				(type default)
			)
			(layer "F.SilkS")
		)
		(fp_line
			(start -0.67945 -0.305054)
			(end -0.12065 -0.305054)
			(stroke
				(width 0.1)
				(type default)
			)
			(layer "F.Fab")
		)
		(fp_line
			(start -0.67945 0.3048)
			(end -0.67945 -0.305054)
			(stroke
				(width 0.1)
				(type default)
			)
			(layer "F.Fab")
		)
		(fp_line
			(start -0.12065 -0.305054)
			(end -0.12065 -0.2794)
			(stroke
				(width 0.1)
				(type default)
			)
			(layer "F.Fab")
		)
		(fp_line
			(start -0.12065 -0.2794)
			(end 0.12065 -0.2794)
			(stroke
				(width 0.1)
				(type default)
			)
			(layer "F.Fab")
		)
		(fp_line
			(start -0.12065 0.2794)
			(end -0.12065 0.3048)
			(stroke
				(width 0.1)
				(type default)
			)
			(layer "F.Fab")
		)
		(fp_line
			(start -0.12065 0.3048)
			(end -0.67945 0.3048)
			(stroke
				(width 0.1)
				(type default)
			)
			(layer "F.Fab")
		)
		(fp_line
			(start 0.120396 0.2794)
			(end -0.12065 0.2794)
			(stroke
				(width 0.1)
				(type default)
			)
			(layer "F.Fab")
		)
		(fp_line
			(start 0.120396 0.3048)
			(end 0.120396 0.2794)
			(stroke
				(width 0.1)
				(type default)
			)
			(layer "F.Fab")
		)
		(fp_line
			(start 0.12065 -0.3048)
			(end 0.67945 -0.3048)
			(stroke
				(width 0.1)
				(type default)
			)
			(layer "F.Fab")
		)
		(fp_line
			(start 0.12065 -0.2794)
			(end 0.12065 -0.3048)
			(stroke
				(width 0.1)
				(type default)
			)
			(layer "F.Fab")
		)
		(fp_line
			(start 0.67945 -0.3048)
			(end 0.67945 0.3048)
			(stroke
				(width 0.1)
				(type default)
			)
			(layer "F.Fab")
		)
		(fp_line
			(start 0.67945 0.3048)
			(end 0.120396 0.3048)
			(stroke
				(width 0.1)
				(type default)
			)
			(layer "F.Fab")
		)
		(pad "1" smd circle
			(at -0.40005 0)
			(size 0 0)
			(layers "F.Cu" "F.Mask" "F.Paste")
			(net "P5V_AUX")
		)
		(pad "2" smd circle
			(at 0.40005 0)
			(size 0 0)
			(layers "F.Cu" "F.Mask" "F.Paste")
			(net "GND")
		)
	)
	(footprint ""
		(layer "F.Cu")
		(at 212.974936 -188.652404 90)
		(property "Reference" "R5303"
			(at 0 0 90)
			(layer "F.SilkS")
			(hide yes)
			(effects
				(font
					(size 1.27 1.27)
				)
			)
		)
		(property "Value" ""
			(at 0 0 90)
			(layer "F.Fab")
			(effects
				(font
					(size 1.27 1.27)
				)
			)
		)
		(duplicate_pad_numbers_are_jumpers no)
		(fp_line
			(start 0.7874 -0.4064)
			(end 0.7874 0.4064)
			(stroke
				(width 0.1524)
				(type default)
			)
			(layer "F.SilkS")
		)
		(fp_line
			(start -0.7874 -0.4064)
			(end 0.7874 -0.4064)
			(stroke
				(width 0.1524)
				(type default)
			)
			(layer "F.SilkS")
		)
		(fp_line
			(start 0.7874 0.4064)
			(end -0.7874 0.4064)
			(stroke
				(width 0.1524)
				(type default)
			)
			(layer "F.SilkS")
		)
		(fp_line
			(start -0.7874 0.4064)
			(end -0.7874 -0.4064)
			(stroke
				(width 0.1524)
				(type default)
			)
			(layer "F.SilkS")
		)
		(fp_line
			(start -0.12065 -0.305054)
			(end -0.12065 -0.2794)
			(stroke
				(width 0.1)
				(type default)
			)
			(layer "F.Fab")
		)
		(fp_line
			(start -0.67945 -0.305054)
			(end -0.12065 -0.305054)
			(stroke
				(width 0.1)
				(type default)
			)
			(layer "F.Fab")
		)
		(fp_line
			(start 0.67945 -0.3048)
			(end 0.67945 0.3048)
			(stroke
				(width 0.1)
				(type default)
			)
			(layer "F.Fab")
		)
		(fp_line
			(start 0.12065 -0.3048)
			(end 0.67945 -0.3048)
			(stroke
				(width 0.1)
				(type default)
			)
			(layer "F.Fab")
		)
		(fp_line
			(start 0.12065 -0.2794)
			(end 0.12065 -0.3048)
			(stroke
				(width 0.1)
				(type default)
			)
			(layer "F.Fab")
		)
		(fp_line
			(start -0.12065 -0.2794)
			(end 0.12065 -0.2794)
			(stroke
				(width 0.1)
				(type default)
			)
			(layer "F.Fab")
		)
		(fp_line
			(start 0.120396 0.2794)
			(end -0.12065 0.2794)
			(stroke
				(width 0.1)
				(type default)
			)
			(layer "F.Fab")
		)
		(fp_line
			(start -0.12065 0.2794)
			(end -0.12065 0.3048)
			(stroke
				(width 0.1)
				(type default)
			)
			(layer "F.Fab")
		)
		(fp_line
			(start 0.67945 0.3048)
			(end 0.120396 0.3048)
			(stroke
				(width 0.1)
				(type default)
			)
			(layer "F.Fab")
		)
		(fp_line
			(start 0.120396 0.3048)
			(end 0.120396 0.2794)
			(stroke
				(width 0.1)
				(type default)
			)
			(layer "F.Fab")
		)
		(fp_line
			(start -0.12065 0.3048)
			(end -0.67945 0.3048)
			(stroke
				(width 0.1)
				(type default)
			)
			(layer "F.Fab")
		)
		(fp_line
			(start -0.67945 0.3048)
			(end -0.67945 -0.305054)
			(stroke
				(width 0.1)
				(type default)
			)
			(layer "F.Fab")
		)
		(pad "1" smd circle
			(at -0.40005 0 90)
			(size 0 0)
			(layers "F.Cu" "F.Mask" "F.Paste")
			(net "BIC_SEL_FLASH_SW2_R")
		)
		(pad "2" smd circle
			(at 0.40005 0 90)
			(size 0 0)
			(layers "F.Cu" "F.Mask" "F.Paste")
			(net "P3V3_AUX")
		)
	)
	(footprint ""
		(layer "F.Cu")
		(at 128.387856 -170.599862 90)
		(property "Reference" "R1090"
			(at 0 0 90)
			(layer "F.SilkS")
			(hide yes)
			(effects
				(font
					(size 1.27 1.27)
				)
			)
		)
		(property "Value" ""
			(at 0 0 90)
			(layer "F.Fab")
			(effects
				(font
					(size 1.27 1.27)
				)
			)
		)
		(duplicate_pad_numbers_are_jumpers no)
		(fp_line
			(start -0.7874 -0.4064)
			(end 0.7874 -0.4064)
			(stroke
				(width 0.1524)
				(type default)
			)
			(layer "F.SilkS")
		)
		(fp_line
			(start -0.12065 -0.305054)
			(end -0.12065 -0.2794)
			(stroke
				(width 0.1)
				(type default)
			)
			(layer "F.Fab")
		)
		(fp_line
			(start -0.67945 -0.305054)
			(end -0.12065 -0.305054)
			(stroke
				(width 0.1)
				(type default)
			)
			(layer "F.Fab")
		)
		(fp_line
			(start 0.67945 -0.3048)
			(end 0.67945 0.3048)
			(stroke
				(width 0.1)
				(type default)
			)
			(layer "F.Fab")
		)
		(fp_line
			(start 0.12065 -0.3048)
			(end 0.67945 -0.3048)
			(stroke
				(width 0.1)
				(type default)
			)
			(layer "F.Fab")
		)
		(fp_line
			(start 0.12065 -0.2794)
			(end 0.12065 -0.3048)
			(stroke
				(width 0.1)
				(type default)
			)
			(layer "F.Fab")
		)
		(fp_line
			(start -0.12065 -0.2794)
			(end 0.12065 -0.2794)
			(stroke
				(width 0.1)
				(type default)
			)
			(layer "F.Fab")
		)
		(fp_line
			(start 0.120396 0.2794)
			(end -0.12065 0.2794)
			(stroke
				(width 0.1)
				(type default)
			)
			(layer "F.Fab")
		)
		(fp_line
			(start -0.12065 0.2794)
			(end -0.12065 0.3048)
			(stroke
				(width 0.1)
				(type default)
			)
			(layer "F.Fab")
		)
		(fp_line
			(start 0.67945 0.3048)
			(end 0.120396 0.3048)
			(stroke
				(width 0.1)
				(type default)
			)
			(layer "F.Fab")
		)
		(fp_line
			(start 0.120396 0.3048)
			(end 0.120396 0.2794)
			(stroke
				(width 0.1)
				(type default)
			)
			(layer "F.Fab")
		)
		(fp_line
			(start -0.12065 0.3048)
			(end -0.67945 0.3048)
			(stroke
				(width 0.1)
				(type default)
			)
			(layer "F.Fab")
		)
		(fp_line
			(start -0.67945 0.3048)
			(end -0.67945 -0.305054)
			(stroke
				(width 0.1)
				(type default)
			)
			(layer "F.Fab")
		)
		(pad "1" smd circle
			(at -0.40005 0 90)
			(size 0 0)
			(layers "F.Cu" "F.Mask" "F.Paste")
			(net "CLK_100M_DB2000QL_PEX2_S1_R_DP")
		)
		(pad "2" smd circle
			(at 0.40005 0 90)
			(size 0 0)
			(layers "F.Cu" "F.Mask" "F.Paste")
			(net "CLK_100M_DB2000QL_PEX2_S1_DP")
		)
	)
	(footprint ""
		(layer "F.Cu")
		(at 456.018138 -278.79929 90)
		(property "Reference" "C827"
			(at 0 0 90)
			(layer "F.SilkS")
			(hide yes)
			(effects
				(font
					(size 1.27 1.27)
				)
			)
		)
		(property "Value" ""
			(at 0 0 90)
			(layer "F.Fab")
			(effects
				(font
					(size 1.27 1.27)
				)
			)
		)
		(duplicate_pad_numbers_are_jumpers no)
		(fp_line
			(start 0.7874 -0.4064)
			(end 0.7874 0.4064)
			(stroke
				(width 0.1524)
				(type default)
			)
			(layer "F.SilkS")
		)
		(fp_line
			(start -0.7874 -0.4064)
			(end 0.7874 -0.4064)
			(stroke
				(width 0.1524)
				(type default)
			)
			(layer "F.SilkS")
		)
		(fp_line
			(start 0.7874 0.4064)
			(end -0.7874 0.4064)
			(stroke
				(width 0.1524)
				(type default)
			)
			(layer "F.SilkS")
		)
		(fp_line
			(start -0.7874 0.4064)
			(end -0.7874 -0.4064)
			(stroke
				(width 0.1524)
				(type default)
			)
			(layer "F.SilkS")
		)
		(fp_line
			(start -0.12065 -0.305054)
			(end -0.12065 -0.2794)
			(stroke
				(width 0.1)
				(type default)
			)
			(layer "F.Fab")
		)
		(fp_line
			(start -0.67945 -0.305054)
			(end -0.12065 -0.305054)
			(stroke
				(width 0.1)
				(type default)
			)
			(layer "F.Fab")
		)
		(fp_line
			(start 0.67945 -0.3048)
			(end 0.67945 0.3048)
			(stroke
				(width 0.1)
				(type default)
			)
			(layer "F.Fab")
		)
		(fp_line
			(start 0.12065 -0.3048)
			(end 0.67945 -0.3048)
			(stroke
				(width 0.1)
				(type default)
			)
			(layer "F.Fab")
		)
		(fp_line
			(start 0.12065 -0.2794)
			(end 0.12065 -0.3048)
			(stroke
				(width 0.1)
				(type default)
			)
			(layer "F.Fab")
		)
		(fp_line
			(start -0.12065 -0.2794)
			(end 0.12065 -0.2794)
			(stroke
				(width 0.1)
				(type default)
			)
			(layer "F.Fab")
		)
		(fp_line
			(start 0.120396 0.2794)
			(end -0.12065 0.2794)
			(stroke
				(width 0.1)
				(type default)
			)
			(layer "F.Fab")
		)
		(fp_line
			(start -0.12065 0.2794)
			(end -0.12065 0.3048)
			(stroke
				(width 0.1)
				(type default)
			)
			(layer "F.Fab")
		)
		(fp_line
			(start 0.67945 0.3048)
			(end 0.120396 0.3048)
			(stroke
				(width 0.1)
				(type default)
			)
			(layer "F.Fab")
		)
		(fp_line
			(start 0.120396 0.3048)
			(end 0.120396 0.2794)
			(stroke
				(width 0.1)
				(type default)
			)
			(layer "F.Fab")
		)
		(fp_line
			(start -0.12065 0.3048)
			(end -0.67945 0.3048)
			(stroke
				(width 0.1)
				(type default)
			)
			(layer "F.Fab")
		)
		(fp_line
			(start -0.67945 0.3048)
			(end -0.67945 -0.305054)
			(stroke
				(width 0.1)
				(type default)
			)
			(layer "F.Fab")
		)
		(pad "1" smd circle
			(at -0.40005 0 90)
			(size 0 0)
			(layers "F.Cu" "F.Mask" "F.Paste")
			(net "P1V25_PEX3_R")
		)
		(pad "2" smd circle
			(at 0.40005 0 90)
			(size 0 0)
			(layers "F.Cu" "F.Mask" "F.Paste")
			(net "GND")
		)
	)
	(footprint ""
		(layer "F.Cu")
		(at 260.249162 -280.994612 -90)
		(property "Reference" "C3400"
			(at 0 0 270)
			(layer "F.SilkS")
			(hide yes)
			(effects
				(font
					(size 1.27 1.27)
				)
			)
		)
		(property "Value" ""
			(at 0 0 270)
			(layer "F.Fab")
			(effects
				(font
					(size 1.27 1.27)
				)
			)
		)
		(duplicate_pad_numbers_are_jumpers no)
		(fp_line
			(start -0.299974 0.150114)
			(end -0.299974 -0.150114)
			(stroke
				(width 0.1)
				(type default)
			)
			(layer "F.Fab")
		)
		(fp_line
			(start 0.299974 0.150114)
			(end -0.299974 0.150114)
			(stroke
				(width 0.1)
				(type default)
			)
			(layer "F.Fab")
		)
		(fp_line
			(start -0.299974 -0.150114)
			(end 0.299974 -0.150114)
			(stroke
				(width 0.1)
				(type default)
			)
			(layer "F.Fab")
		)
		(fp_line
			(start 0.299974 -0.150114)
			(end 0.299974 0.150114)
			(stroke
				(width 0.1)
				(type default)
			)
			(layer "F.Fab")
		)
		(pad "1" smd rect
			(at -0.2667 0 270)
			(size 0.3048 0.381)
			(layers "F.Cu" "F.Mask" "F.Paste")
			(net "P1V8_PLL0_PEX2")
		)
		(pad "2" smd rect
			(at 0.2667 0 270)
			(size 0.3048 0.381)
			(layers "F.Cu" "F.Mask" "F.Paste")
			(net "GND")
		)
	)
	(footprint ""
		(layer "F.Cu")
		(at 326.694038 -116.410486)
		(property "Reference" "PR7101"
			(at 0 0 0)
			(layer "F.SilkS")
			(hide yes)
			(effects
				(font
					(size 1.27 1.27)
				)
			)
		)
		(property "Value" ""
			(at 0 0 0)
			(layer "F.Fab")
			(effects
				(font
					(size 1.27 1.27)
				)
			)
		)
		(duplicate_pad_numbers_are_jumpers no)
		(fp_line
			(start -0.7874 -0.4064)
			(end 0.7874 -0.4064)
			(stroke
				(width 0.1524)
				(type default)
			)
			(layer "F.SilkS")
		)
		(fp_line
			(start -0.7874 0.4064)
			(end -0.7874 -0.4064)
			(stroke
				(width 0.1524)
				(type default)
			)
			(layer "F.SilkS")
		)
		(fp_line
			(start 0.7874 -0.4064)
			(end 0.7874 0.4064)
			(stroke
				(width 0.1524)
				(type default)
			)
			(layer "F.SilkS")
		)
		(fp_line
			(start 0.7874 0.4064)
			(end -0.7874 0.4064)
			(stroke
				(width 0.1524)
				(type default)
			)
			(layer "F.SilkS")
		)
		(fp_line
			(start -0.67945 -0.305054)
			(end -0.12065 -0.305054)
			(stroke
				(width 0.1)
				(type default)
			)
			(layer "F.Fab")
		)
		(fp_line
			(start -0.67945 0.3048)
			(end -0.67945 -0.305054)
			(stroke
				(width 0.1)
				(type default)
			)
			(layer "F.Fab")
		)
		(fp_line
			(start -0.12065 -0.305054)
			(end -0.12065 -0.2794)
			(stroke
				(width 0.1)
				(type default)
			)
			(layer "F.Fab")
		)
		(fp_line
			(start -0.12065 -0.2794)
			(end 0.12065 -0.2794)
			(stroke
				(width 0.1)
				(type default)
			)
			(layer "F.Fab")
		)
		(fp_line
			(start -0.12065 0.2794)
			(end -0.12065 0.3048)
			(stroke
				(width 0.1)
				(type default)
			)
			(layer "F.Fab")
		)
		(fp_line
			(start -0.12065 0.3048)
			(end -0.67945 0.3048)
			(stroke
				(width 0.1)
				(type default)
			)
			(layer "F.Fab")
		)
		(fp_line
			(start 0.120396 0.2794)
			(end -0.12065 0.2794)
			(stroke
				(width 0.1)
				(type default)
			)
			(layer "F.Fab")
		)
		(fp_line
			(start 0.120396 0.3048)
			(end 0.120396 0.2794)
			(stroke
				(width 0.1)
				(type default)
			)
			(layer "F.Fab")
		)
		(fp_line
			(start 0.12065 -0.3048)
			(end 0.67945 -0.3048)
			(stroke
				(width 0.1)
				(type default)
			)
			(layer "F.Fab")
		)
		(fp_line
			(start 0.12065 -0.2794)
			(end 0.12065 -0.3048)
			(stroke
				(width 0.1)
				(type default)
			)
			(layer "F.Fab")
		)
		(fp_line
			(start 0.67945 -0.3048)
			(end 0.67945 0.3048)
			(stroke
				(width 0.1)
				(type default)
			)
			(layer "F.Fab")
		)
		(fp_line
			(start 0.67945 0.3048)
			(end 0.120396 0.3048)
			(stroke
				(width 0.1)
				(type default)
			)
			(layer "F.Fab")
		)
		(pad "1" smd circle
			(at -0.40005 0)
			(size 0 0)
			(layers "F.Cu" "F.Mask" "F.Paste")
			(net "P3V3_NIC5_CO_MODE")
		)
		(pad "2" smd circle
			(at 0.40005 0)
			(size 0 0)
			(layers "F.Cu" "F.Mask" "F.Paste")
			(net "GND")
		)
	)
	(footprint ""
		(layer "F.Cu")
		(at 259.53212 -32.848042 90)
		(property "Reference" "PC947"
			(at 0 0 90)
			(layer "F.SilkS")
			(hide yes)
			(effects
				(font
					(size 1.27 1.27)
				)
			)
		)
		(property "Value" ""
			(at 0 0 90)
			(layer "F.Fab")
			(effects
				(font
					(size 1.27 1.27)
				)
			)
		)
		(duplicate_pad_numbers_are_jumpers no)
		(fp_line
			(start 0.7874 -0.4064)
			(end 0.7874 0.4064)
			(stroke
				(width 0.1524)
				(type default)
			)
			(layer "F.SilkS")
		)
		(fp_line
			(start -0.7874 -0.4064)
			(end 0.7874 -0.4064)
			(stroke
				(width 0.1524)
				(type default)
			)
			(layer "F.SilkS")
		)
		(fp_line
			(start 0.7874 0.4064)
			(end -0.7874 0.4064)
			(stroke
				(width 0.1524)
				(type default)
			)
			(layer "F.SilkS")
		)
		(fp_line
			(start -0.7874 0.4064)
			(end -0.7874 -0.4064)
			(stroke
				(width 0.1524)
				(type default)
			)
			(layer "F.SilkS")
		)
		(fp_line
			(start -0.12065 -0.305054)
			(end -0.12065 -0.2794)
			(stroke
				(width 0.1)
				(type default)
			)
			(layer "F.Fab")
		)
		(fp_line
			(start -0.67945 -0.305054)
			(end -0.12065 -0.305054)
			(stroke
				(width 0.1)
				(type default)
			)
			(layer "F.Fab")
		)
		(fp_line
			(start 0.67945 -0.3048)
			(end 0.67945 0.3048)
			(stroke
				(width 0.1)
				(type default)
			)
			(layer "F.Fab")
		)
		(fp_line
			(start 0.12065 -0.3048)
			(end 0.67945 -0.3048)
			(stroke
				(width 0.1)
				(type default)
			)
			(layer "F.Fab")
		)
		(fp_line
			(start 0.12065 -0.2794)
			(end 0.12065 -0.3048)
			(stroke
				(width 0.1)
				(type default)
			)
			(layer "F.Fab")
		)
		(fp_line
			(start -0.12065 -0.2794)
			(end 0.12065 -0.2794)
			(stroke
				(width 0.1)
				(type default)
			)
			(layer "F.Fab")
		)
		(fp_line
			(start 0.120396 0.2794)
			(end -0.12065 0.2794)
			(stroke
				(width 0.1)
				(type default)
			)
			(layer "F.Fab")
		)
		(fp_line
			(start -0.12065 0.2794)
			(end -0.12065 0.3048)
			(stroke
				(width 0.1)
				(type default)
			)
			(layer "F.Fab")
		)
		(fp_line
			(start 0.67945 0.3048)
			(end 0.120396 0.3048)
			(stroke
				(width 0.1)
				(type default)
			)
			(layer "F.Fab")
		)
		(fp_line
			(start 0.120396 0.3048)
			(end 0.120396 0.2794)
			(stroke
				(width 0.1)
				(type default)
			)
			(layer "F.Fab")
		)
		(fp_line
			(start -0.12065 0.3048)
			(end -0.67945 0.3048)
			(stroke
				(width 0.1)
				(type default)
			)
			(layer "F.Fab")
		)
		(fp_line
			(start -0.67945 0.3048)
			(end -0.67945 -0.305054)
			(stroke
				(width 0.1)
				(type default)
			)
			(layer "F.Fab")
		)
		(pad "1" smd circle
			(at -0.40005 0 90)
			(size 0 0)
			(layers "F.Cu" "F.Mask" "F.Paste")
			(net "P3V3_SSD9_CO_DV_DT")
		)
		(pad "2" smd circle
			(at 0.40005 0 90)
			(size 0 0)
			(layers "F.Cu" "F.Mask" "F.Paste")
			(net "GND")
		)
	)
)
